(kicad_pcb
	(version 20260206)
	(generator "pcbnew")
	(generator_version "10.0")
	(general
		(thickness 1.6)
		(legacy_teardrops no)
	)
	(paper "A4")
	(title_block
		(title "Bryce Canyon_IOM_M2_16342-2_OCP.brd")
		(comment 1 "Bryce Canyon / footprints 405-411 of 1146")
	)
	(layers
		(0 "F.Cu" signal "TOP")
		(4 "In1.Cu" signal "L2GND")
		(6 "In2.Cu" signal "L3")
		(8 "In3.Cu" signal "L4VCC")
		(10 "In4.Cu" signal "L5VCC")
		(12 "In5.Cu" signal "L6")
		(14 "In6.Cu" signal "L7GND")
		(2 "B.Cu" signal "BOTTOM")
		(9 "F.Adhes" user "F.Adhesive")
		(11 "B.Adhes" user "B.Adhesive")
		(13 "F.Paste" user "Package Geometry/Pastemask Top")
		(15 "B.Paste" user "Package Geometry/Pastemask Bottom")
		(5 "F.SilkS" user "Ref Des/Silkscreen Top")
		(7 "B.SilkS" user "Ref Des/Silkscreen Bottom")
		(1 "F.Mask" user "Board Geometry/Soldermask Top")
		(3 "B.Mask" user "Board Geometry/Soldermask Bottom")
		(17 "Dwgs.User" user "User.Drawings")
		(19 "Cmts.User" user "User.Comments")
		(21 "Eco1.User" user "User.Eco1")
		(23 "Eco2.User" user "User.Eco2")
		(25 "Edge.Cuts" user "Board Geometry/Outline")
		(27 "Margin" user)
		(31 "F.CrtYd" user "Package Geometry/Place Bound Top")
		(29 "B.CrtYd" user "Package Geometry/Place Bound Bottom")
		(35 "F.Fab" user "Ref Des/Assembly Top")
		(33 "B.Fab" user "Ref Des/Assembly Bottom")
	)
	(footprint ""
		(layer "F.Cu")
		(at 215.330024 -87.56396 90)
		(property "Reference" "R836"
			(at 0 0 90)
			(layer "F.SilkS")
			(hide yes)
			(effects
				(font
					(size 1.27 1.27)
				)
			)
		)
		(property "Value" "2KR2F-3-GP"
			(at 0.064008 -3.993896 90)
			(unlocked yes)
			(layer "F.Fab")
			(hide yes)
			(effects
				(font
					(size 1.016 1.016)
					(thickness 0.1524)
				)
			)
		)
		(property "Device Type" "R402H16"
			(at 0.064008 -5.517896 90)
			(unlocked yes)
			(layer "F.Fab")
			(hide yes)
			(effects
				(font
					(size 1.016 1.016)
					(thickness 0.1524)
				)
			)
		)
		(duplicate_pad_numbers_are_jumpers no)
		(fp_line
			(start 0.508 -0.9398)
			(end -0.508 -0.9398)
			(stroke
				(width 0.1524)
				(type default)
			)
			(layer "F.SilkS")
		)
		(fp_line
			(start -0.508 -0.9398)
			(end -0.508 0.9398)
			(stroke
				(width 0.1524)
				(type default)
			)
			(layer "F.SilkS")
		)
		(fp_rect
			(start -0.508 0.9398)
			(end 0.508 -0.9398)
			(stroke
				(width 0)
				(type default)
			)
			(fill no)
			(layer "F.CrtYd")
		)
		(fp_rect
			(start -0.508 0.9398)
			(end 0.508 -0.9398)
			(stroke
				(width 0)
				(type default)
			)
			(fill no)
			(layer "F.Fab")
		)
		(pad "1" smd custom
			(at 0 -0.4445 90)
			(size 0.1397 0.1397)
			(layers "F.Cu" "F.Mask" "F.Paste")
			(net "P3V3_M2_LL_R")
			(options
				(clearance outline)
				(anchor circle)
			)
			(primitives
				(gr_poly
					(pts
						(arc
							(start -0.1778 -0.2794)
							(mid -0.249642 -0.249642)
							(end -0.2794 -0.1778)
						)
						(arc
							(start -0.2794 0.1778)
							(mid -0.249642 0.249642)
							(end -0.1778 0.2794)
						)
						(arc
							(start 0.1778 0.2794)
							(mid 0.249642 0.249642)
							(end 0.2794 0.1778)
						)
						(arc
							(start 0.2794 -0.1778)
							(mid 0.249642 -0.249642)
							(end 0.1778 -0.2794)
						)
					)
					(width 0)
					(fill yes)
				)
			)
		)
		(pad "2" smd custom
			(at 0 0.4445 90)
			(size 0.1397 0.1397)
			(layers "F.Cu" "F.Mask" "F.Paste")
			(net "P3V3_M2_LL")
			(options
				(clearance outline)
				(anchor circle)
			)
			(primitives
				(gr_poly
					(pts
						(arc
							(start -0.1778 -0.2794)
							(mid -0.249642 -0.249642)
							(end -0.2794 -0.1778)
						)
						(arc
							(start -0.2794 0.1778)
							(mid -0.249642 0.249642)
							(end -0.1778 0.2794)
						)
						(arc
							(start 0.1778 0.2794)
							(mid 0.249642 0.249642)
							(end 0.2794 0.1778)
						)
						(arc
							(start 0.2794 -0.1778)
							(mid 0.249642 -0.249642)
							(end 0.1778 -0.2794)
						)
					)
					(width 0)
					(fill yes)
				)
			)
		)
	)
	(footprint ""
		(layer "F.Cu")
		(at 64.83604 -150.76805 -90)
		(property "Reference" "R766"
			(at 0 0 270)
			(layer "F.SilkS")
			(hide yes)
			(effects
				(font
					(size 1.27 1.27)
				)
			)
		)
		(property "Value" "33R2J-2-GP"
			(at 0.064008 -3.993896 270)
			(unlocked yes)
			(layer "F.Fab")
			(hide yes)
			(effects
				(font
					(size 1.016 1.016)
					(thickness 0.1524)
				)
			)
		)
		(property "Device Type" "R402H16"
			(at 0.064008 -5.517896 270)
			(unlocked yes)
			(layer "F.Fab")
			(hide yes)
			(effects
				(font
					(size 1.016 1.016)
					(thickness 0.1524)
				)
			)
		)
		(duplicate_pad_numbers_are_jumpers no)
		(fp_line
			(start -0.508 -0.9398)
			(end -0.508 0.9398)
			(stroke
				(width 0.1524)
				(type default)
			)
			(layer "F.SilkS")
		)
		(fp_line
			(start 0.508 -0.9398)
			(end -0.508 -0.9398)
			(stroke
				(width 0.1524)
				(type default)
			)
			(layer "F.SilkS")
		)
		(fp_rect
			(start -0.508 0.9398)
			(end 0.508 -0.9398)
			(stroke
				(width 0)
				(type default)
			)
			(fill no)
			(layer "F.CrtYd")
		)
		(fp_rect
			(start -0.508 0.9398)
			(end 0.508 -0.9398)
			(stroke
				(width 0)
				(type default)
			)
			(fill no)
			(layer "F.Fab")
		)
		(pad "1" smd custom
			(at 0 -0.4445 270)
			(size 0.1397 0.1397)
			(layers "F.Cu" "F.Mask" "F.Paste")
			(net "U30_Q1")
			(options
				(clearance outline)
				(anchor circle)
			)
			(primitives
				(gr_poly
					(pts
						(arc
							(start -0.1778 -0.2794)
							(mid -0.249642 -0.249642)
							(end -0.2794 -0.1778)
						)
						(arc
							(start -0.2794 0.1778)
							(mid -0.249642 0.249642)
							(end -0.1778 0.2794)
						)
						(arc
							(start 0.1778 0.2794)
							(mid 0.249642 0.249642)
							(end 0.2794 0.1778)
						)
						(arc
							(start 0.2794 -0.1778)
							(mid 0.249642 -0.249642)
							(end 0.1778 -0.2794)
						)
					)
					(width 0)
					(fill yes)
				)
			)
		)
		(pad "2" smd custom
			(at 0 0.4445 270)
			(size 0.1397 0.1397)
			(layers "F.Cu" "F.Mask" "F.Paste")
			(net "CLK_50M_BMC_NCSI")
			(options
				(clearance outline)
				(anchor circle)
			)
			(primitives
				(gr_poly
					(pts
						(arc
							(start -0.1778 -0.2794)
							(mid -0.249642 -0.249642)
							(end -0.2794 -0.1778)
						)
						(arc
							(start -0.2794 0.1778)
							(mid -0.249642 0.249642)
							(end -0.1778 0.2794)
						)
						(arc
							(start 0.1778 0.2794)
							(mid 0.249642 0.249642)
							(end 0.2794 0.1778)
						)
						(arc
							(start 0.2794 -0.1778)
							(mid 0.249642 -0.249642)
							(end 0.1778 -0.2794)
						)
					)
					(width 0)
					(fill yes)
				)
			)
		)
	)
	(footprint ""
		(layer "F.Cu")
		(at 91.639644 -162.52952 -90)
		(property "Reference" "C17"
			(at 0 0 270)
			(layer "F.SilkS")
			(hide yes)
			(effects
				(font
					(size 1.27 1.27)
				)
			)
		)
		(property "Value" "SC18P50V2JN-1-GP"
			(at 1.1811 -2.7051 270)
			(unlocked yes)
			(layer "F.Fab")
			(hide yes)
			(effects
				(font
					(size 1.016 1.016)
					(thickness 0.1524)
				)
			)
		)
		(property "Device Type" "C402H22"
			(at 1.1811 -4.2291 270)
			(unlocked yes)
			(layer "F.Fab")
			(hide yes)
			(effects
				(font
					(size 1.016 1.016)
					(thickness 0.1524)
				)
			)
		)
		(duplicate_pad_numbers_are_jumpers no)
		(fp_rect
			(start -0.4318 0.9525)
			(end 0.4318 -0.9525)
			(stroke
				(width 0)
				(type default)
			)
			(fill no)
			(layer "F.CrtYd")
		)
		(fp_rect
			(start -0.4318 0.9525)
			(end 0.4318 -0.9525)
			(stroke
				(width 0)
				(type default)
			)
			(fill no)
			(layer "F.Fab")
		)
		(pad "1" smd custom
			(at 0 -0.4445 270)
			(size 0.1524 0.1524)
			(layers "F.Cu" "F.Mask" "F.Paste")
			(net "USB_HUB_XTAL_IN")
			(options
				(clearance outline)
				(anchor circle)
			)
			(primitives
				(gr_poly
					(pts
						(arc
							(start 0.3048 -0.2032)
							(mid 0.275042 -0.275042)
							(end 0.2032 -0.3048)
						)
						(arc
							(start -0.2032 -0.3048)
							(mid -0.275042 -0.275042)
							(end -0.3048 -0.2032)
						)
						(arc
							(start -0.3048 0.2032)
							(mid -0.275042 0.275042)
							(end -0.2032 0.3048)
						)
						(arc
							(start 0.2032 0.3048)
							(mid 0.275042 0.275042)
							(end 0.3048 0.2032)
						)
					)
					(width 0)
					(fill yes)
				)
			)
		)
		(pad "2" smd custom
			(at 0 0.4445 270)
			(size 0.1524 0.1524)
			(layers "F.Cu" "F.Mask" "F.Paste")
			(net "GND")
			(options
				(clearance outline)
				(anchor circle)
			)
			(primitives
				(gr_poly
					(pts
						(arc
							(start 0.3048 -0.2032)
							(mid 0.275042 -0.275042)
							(end 0.2032 -0.3048)
						)
						(arc
							(start -0.2032 -0.3048)
							(mid -0.275042 -0.275042)
							(end -0.3048 -0.2032)
						)
						(arc
							(start -0.3048 0.2032)
							(mid -0.275042 0.275042)
							(end -0.2032 0.3048)
						)
						(arc
							(start 0.2032 0.3048)
							(mid 0.275042 0.275042)
							(end 0.3048 0.2032)
						)
					)
					(width 0)
					(fill yes)
				)
			)
		)
	)
	(footprint ""
		(layer "F.Cu")
		(at 32.6898 -134.6962 90)
		(property "Reference" "R369"
			(at 0 0 90)
			(layer "F.SilkS")
			(hide yes)
			(effects
				(font
					(size 1.27 1.27)
				)
			)
		)
		(property "Value" "4K7R2F-GP"
			(at 0.064008 -3.993896 90)
			(unlocked yes)
			(layer "F.Fab")
			(hide yes)
			(effects
				(font
					(size 1.016 1.016)
					(thickness 0.1524)
				)
			)
		)
		(property "Device Type" "R402H16"
			(at 0.064008 -5.517896 90)
			(unlocked yes)
			(layer "F.Fab")
			(hide yes)
			(effects
				(font
					(size 1.016 1.016)
					(thickness 0.1524)
				)
			)
		)
		(duplicate_pad_numbers_are_jumpers no)
		(fp_line
			(start 0.508 -0.9398)
			(end -0.508 -0.9398)
			(stroke
				(width 0.1524)
				(type default)
			)
			(layer "F.SilkS")
		)
		(fp_line
			(start -0.508 -0.9398)
			(end -0.508 0.9398)
			(stroke
				(width 0.1524)
				(type default)
			)
			(layer "F.SilkS")
		)
		(fp_rect
			(start -0.508 0.9398)
			(end 0.508 -0.9398)
			(stroke
				(width 0)
				(type default)
			)
			(fill no)
			(layer "F.CrtYd")
		)
		(fp_rect
			(start -0.508 0.9398)
			(end 0.508 -0.9398)
			(stroke
				(width 0)
				(type default)
			)
			(fill no)
			(layer "F.Fab")
		)
		(pad "1" smd custom
			(at 0 -0.4445 90)
			(size 0.1397 0.1397)
			(layers "F.Cu" "F.Mask" "F.Paste")
			(net "P3V3_STBY")
			(options
				(clearance outline)
				(anchor circle)
			)
			(primitives
				(gr_poly
					(pts
						(arc
							(start -0.1778 -0.2794)
							(mid -0.249642 -0.249642)
							(end -0.2794 -0.1778)
						)
						(arc
							(start -0.2794 0.1778)
							(mid -0.249642 0.249642)
							(end -0.1778 0.2794)
						)
						(arc
							(start 0.1778 0.2794)
							(mid 0.249642 0.249642)
							(end 0.2794 0.1778)
						)
						(arc
							(start 0.2794 -0.1778)
							(mid 0.249642 -0.249642)
							(end 0.1778 -0.2794)
						)
					)
					(width 0)
					(fill yes)
				)
			)
		)
		(pad "2" smd custom
			(at 0 0.4445 90)
			(size 0.1397 0.1397)
			(layers "F.Cu" "F.Mask" "F.Paste")
			(net "BMC_SPI_CLK")
			(options
				(clearance outline)
				(anchor circle)
			)
			(primitives
				(gr_poly
					(pts
						(arc
							(start -0.1778 -0.2794)
							(mid -0.249642 -0.249642)
							(end -0.2794 -0.1778)
						)
						(arc
							(start -0.2794 0.1778)
							(mid -0.249642 0.249642)
							(end -0.1778 0.2794)
						)
						(arc
							(start 0.1778 0.2794)
							(mid 0.249642 0.249642)
							(end 0.2794 0.1778)
						)
						(arc
							(start 0.2794 -0.1778)
							(mid 0.249642 -0.249642)
							(end 0.1778 -0.2794)
						)
					)
					(width 0)
					(fill yes)
				)
			)
		)
	)
	(footprint ""
		(layer "F.Cu")
		(at 94.98838 -20.7518 90)
		(property "Reference" "D16"
			(at 0 0 90)
			(layer "F.SilkS")
			(hide yes)
			(effects
				(font
					(size 1.27 1.27)
				)
			)
		)
		(property "Value" "PESD5V0S1BL-1-GP"
			(at 1.8923 -1.5621 90)
			(unlocked yes)
			(layer "F.Fab")
			(hide yes)
			(effects
				(font
					(size 1.016 1.016)
					(thickness 0.1524)
				)
			)
		)
		(property "Device Type" "SOD882-10D6-1H20"
			(at 1.8923 -3.0861 90)
			(unlocked yes)
			(layer "F.Fab")
			(hide yes)
			(effects
				(font
					(size 1.016 1.016)
					(thickness 0.1524)
				)
			)
		)
		(duplicate_pad_numbers_are_jumpers no)
		(fp_line
			(start -0.3048 -0.9271)
			(end 0.3048 -0.9271)
			(stroke
				(width 0.254)
				(type default)
			)
			(layer "F.SilkS")
		)
		(fp_rect
			(start -0.2921 0.4953)
			(end 0.2921 -0.4953)
			(stroke
				(width 0)
				(type default)
			)
			(fill no)
			(layer "F.CrtYd")
		)
		(fp_poly
			(pts
				(xy -0.4318 0.8001) (xy -0.4318 -0.266192) (xy -0.2921 -0.266192) (xy -0.2921 0.4953) (xy 0.2921 0.4953)
				(xy 0.2921 -0.4953) (xy -0.2921 -0.4953) (xy -0.2921 -0.2667) (xy -0.4318 -0.2667) (xy -0.4318 -0.8001)
				(xy 0.4318 -0.8001) (xy 0.4318 0.8001)
			)
			(stroke
				(width 0)
				(type default)
			)
			(fill no)
			(layer "F.CrtYd")
		)
		(fp_rect
			(start -0.4318 0.8001)
			(end 0.4318 -0.8001)
			(stroke
				(width 0)
				(type default)
			)
			(fill no)
			(layer "F.Fab")
		)
		(pad "1" smd custom
			(at 0 -0.4445 90)
			(size 0.1143 0.1143)
			(layers "F.Cu" "F.Mask" "F.Paste")
			(net "UART_IOM_TX")
			(options
				(clearance outline)
				(anchor circle)
			)
			(primitives
				(gr_poly
					(pts
						(arc
							(start -0.2032 0.2286)
							(mid -0.275042 0.198842)
							(end -0.3048 0.127)
						)
						(arc
							(start -0.3048 -0.127)
							(mid -0.275042 -0.198842)
							(end -0.2032 -0.2286)
						)
						(arc
							(start 0.2032 -0.2286)
							(mid 0.275042 -0.198842)
							(end 0.3048 -0.127)
						)
						(arc
							(start 0.3048 0.127)
							(mid 0.275042 0.198842)
							(end 0.2032 0.2286)
						)
					)
					(width 0)
					(fill yes)
				)
			)
		)
		(pad "2" smd custom
			(at 0 0.4445 90)
			(size 0.1143 0.1143)
			(layers "F.Cu" "F.Mask" "F.Paste")
			(net "GND")
			(options
				(clearance outline)
				(anchor circle)
			)
			(primitives
				(gr_poly
					(pts
						(arc
							(start 0.2032 -0.2286)
							(mid 0.275042 -0.198842)
							(end 0.3048 -0.127)
						)
						(arc
							(start 0.3048 0.127)
							(mid 0.275042 0.198842)
							(end 0.2032 0.2286)
						)
						(arc
							(start -0.2032 0.2286)
							(mid -0.275042 0.198842)
							(end -0.3048 0.127)
						)
						(arc
							(start -0.3048 -0.127)
							(mid -0.275042 -0.198842)
							(end -0.2032 -0.2286)
						)
					)
					(width 0)
					(fill yes)
				)
			)
		)
	)
	(footprint ""
		(layer "F.Cu")
		(at 48.533304 -161.264092 180)
		(property "Reference" "R203"
			(at 0 0 180)
			(layer "F.SilkS")
			(hide yes)
			(effects
				(font
					(size 1.27 1.27)
				)
			)
		)
		(property "Value" "2K2R2F-GP"
			(at 0.064008 -3.993896 180)
			(unlocked yes)
			(layer "F.Fab")
			(hide yes)
			(effects
				(font
					(size 1.016 1.016)
					(thickness 0.1524)
				)
			)
		)
		(property "Device Type" "R402H16"
			(at 0.064008 -5.517896 180)
			(unlocked yes)
			(layer "F.Fab")
			(hide yes)
			(effects
				(font
					(size 1.016 1.016)
					(thickness 0.1524)
				)
			)
		)
		(duplicate_pad_numbers_are_jumpers no)
		(fp_line
			(start 0.508 -0.9398)
			(end -0.508 -0.9398)
			(stroke
				(width 0.1524)
				(type default)
			)
			(layer "F.SilkS")
		)
		(fp_line
			(start -0.508 -0.9398)
			(end -0.508 0.9398)
			(stroke
				(width 0.1524)
				(type default)
			)
			(layer "F.SilkS")
		)
		(fp_rect
			(start -0.508 0.9398)
			(end 0.508 -0.9398)
			(stroke
				(width 0)
				(type default)
			)
			(fill no)
			(layer "F.CrtYd")
		)
		(fp_rect
			(start -0.508 0.9398)
			(end 0.508 -0.9398)
			(stroke
				(width 0)
				(type default)
			)
			(fill no)
			(layer "F.Fab")
		)
		(pad "1" smd custom
			(at 0 -0.4445 180)
			(size 0.1397 0.1397)
			(layers "F.Cu" "F.Mask" "F.Paste")
			(net "I2C_DPB_MISC_SCL_OUT")
			(options
				(clearance outline)
				(anchor circle)
			)
			(primitives
				(gr_poly
					(pts
						(arc
							(start -0.1778 -0.2794)
							(mid -0.249642 -0.249642)
							(end -0.2794 -0.1778)
						)
						(arc
							(start -0.2794 0.1778)
							(mid -0.249642 0.249642)
							(end -0.1778 0.2794)
						)
						(arc
							(start 0.1778 0.2794)
							(mid 0.249642 0.249642)
							(end 0.2794 0.1778)
						)
						(arc
							(start 0.2794 -0.1778)
							(mid 0.249642 -0.249642)
							(end 0.1778 -0.2794)
						)
					)
					(width 0)
					(fill yes)
				)
			)
		)
		(pad "2" smd custom
			(at 0 0.4445 180)
			(size 0.1397 0.1397)
			(layers "F.Cu" "F.Mask" "F.Paste")
			(net "P3V3_STBY")
			(options
				(clearance outline)
				(anchor circle)
			)
			(primitives
				(gr_poly
					(pts
						(arc
							(start -0.1778 -0.2794)
							(mid -0.249642 -0.249642)
							(end -0.2794 -0.1778)
						)
						(arc
							(start -0.2794 0.1778)
							(mid -0.249642 0.249642)
							(end -0.1778 0.2794)
						)
						(arc
							(start 0.1778 0.2794)
							(mid 0.249642 0.249642)
							(end 0.2794 0.1778)
						)
						(arc
							(start 0.2794 -0.1778)
							(mid 0.249642 -0.249642)
							(end 0.1778 -0.2794)
						)
					)
					(width 0)
					(fill yes)
				)
			)
		)
	)
	(footprint ""
		(layer "F.Cu")
		(at 19.15287 -131.007358 180)
		(property "Reference" "R216"
			(at 0 0 180)
			(layer "F.SilkS")
			(hide yes)
			(effects
				(font
					(size 1.27 1.27)
				)
			)
		)
		(property "Value" "120R2F-GP"
			(at 0.064008 -3.993896 180)
			(unlocked yes)
			(layer "F.Fab")
			(hide yes)
			(effects
				(font
					(size 1.016 1.016)
					(thickness 0.1524)
				)
			)
		)
		(property "Device Type" "R402H16"
			(at 0.064008 -5.517896 180)
			(unlocked yes)
			(layer "F.Fab")
			(hide yes)
			(effects
				(font
					(size 1.016 1.016)
					(thickness 0.1524)
				)
			)
		)
		(duplicate_pad_numbers_are_jumpers no)
		(fp_line
			(start 0.508 -0.9398)
			(end -0.508 -0.9398)
			(stroke
				(width 0.1524)
				(type default)
			)
			(layer "F.SilkS")
		)
		(fp_line
			(start -0.508 -0.9398)
			(end -0.508 0.9398)
			(stroke
				(width 0.1524)
				(type default)
			)
			(layer "F.SilkS")
		)
		(fp_rect
			(start -0.508 0.9398)
			(end 0.508 -0.9398)
			(stroke
				(width 0)
				(type default)
			)
			(fill no)
			(layer "F.CrtYd")
		)
		(fp_rect
			(start -0.508 0.9398)
			(end 0.508 -0.9398)
			(stroke
				(width 0)
				(type default)
			)
			(fill no)
			(layer "F.Fab")
		)
		(pad "1" smd custom
			(at 0 -0.4445 180)
			(size 0.1397 0.1397)
			(layers "F.Cu" "F.Mask" "F.Paste")
			(net "MEMCSN")
			(options
				(clearance outline)
				(anchor circle)
			)
			(primitives
				(gr_poly
					(pts
						(arc
							(start -0.1778 -0.2794)
							(mid -0.249642 -0.249642)
							(end -0.2794 -0.1778)
						)
						(arc
							(start -0.2794 0.1778)
							(mid -0.249642 0.249642)
							(end -0.1778 0.2794)
						)
						(arc
							(start 0.1778 0.2794)
							(mid 0.249642 0.249642)
							(end 0.2794 0.1778)
						)
						(arc
							(start 0.2794 -0.1778)
							(mid 0.249642 -0.249642)
							(end 0.1778 -0.2794)
						)
					)
					(width 0)
					(fill yes)
				)
			)
		)
		(pad "2" smd custom
			(at 0 0.4445 180)
			(size 0.1397 0.1397)
			(layers "F.Cu" "F.Mask" "F.Paste")
			(net "P1V2_STBY")
			(options
				(clearance outline)
				(anchor circle)
			)
			(primitives
				(gr_poly
					(pts
						(arc
							(start -0.1778 -0.2794)
							(mid -0.249642 -0.249642)
							(end -0.2794 -0.1778)
						)
						(arc
							(start -0.2794 0.1778)
							(mid -0.249642 0.249642)
							(end -0.1778 0.2794)
						)
						(arc
							(start 0.1778 0.2794)
							(mid 0.249642 0.249642)
							(end 0.2794 0.1778)
						)
						(arc
							(start 0.2794 -0.1778)
							(mid 0.249642 -0.249642)
							(end 0.1778 -0.2794)
						)
					)
					(width 0)
					(fill yes)
				)
			)
		)
	)
)
